(kicad_pcb
	(version 20260206)
	(generator "pcbnew")
	(generator_version "10.0")
	(general
		(thickness 1.6)
		(legacy_teardrops no)
	)
	(paper "A4")
	(title_block
		(title "peb — Lightning_PEB_BRD.brd")
		(comment 1 "Lightning (Wiwynn / Facebook NVMe JBOF) / footprints 491-495 of 2563")
	)
	(layers
		(0 "F.Cu" signal "TOP")
		(4 "In1.Cu" signal "L2GND")
		(6 "In2.Cu" signal "L3")
		(8 "In3.Cu" signal "L4VCC")
		(10 "In4.Cu" signal "L5VCC")
		(12 "In5.Cu" signal "L6")
		(14 "In6.Cu" signal "L7GND")
		(2 "B.Cu" signal "BOTTOM")
		(9 "F.Adhes" user "F.Adhesive")
		(11 "B.Adhes" user "B.Adhesive")
		(13 "F.Paste" user "Package Geometry/Pastemask Top")
		(15 "B.Paste" user "Package Geometry/Pastemask Bottom")
		(5 "F.SilkS" user "Ref Des/Silkscreen Top")
		(7 "B.SilkS" user "Ref Des/Silkscreen Bottom")
		(1 "F.Mask" user "Board Geometry/Soldermask Top")
		(3 "B.Mask" user "Board Geometry/Soldermask Bottom")
		(17 "Dwgs.User" user "User.Drawings")
		(19 "Cmts.User" user "User.Comments")
		(21 "Eco1.User" user "User.Eco1")
		(23 "Eco2.User" user "User.Eco2")
		(25 "Edge.Cuts" user "Board Geometry/Outline")
		(27 "Margin" user)
		(31 "F.CrtYd" user "Package Geometry/Place Bound Top")
		(29 "B.CrtYd" user "Package Geometry/Place Bound Bottom")
		(35 "F.Fab" user "Ref Des/Assembly Top")
		(33 "B.Fab" user "Ref Des/Assembly Bottom")
	)
	(footprint ""
		(layer "F.Cu")
		(at 180.600096 -17.500092 -90)
		(property "Reference" "LED18"
			(at 0 0 270)
			(layer "F.SilkS")
			(hide yes)
			(effects
				(font
					(size 1.27 1.27)
				)
			)
		)
		(property "Value" "LED-YG-51-GP"
			(at -2.6924 -1.4224 270)
			(unlocked yes)
			(layer "F.Fab")
			(hide yes)
			(effects
				(font
					(size 1.016 1.016)
					(thickness 0.1524)
				)
			)
		)
		(property "Device Type" "LED1608AKH40"
			(at -2.6924 -2.9464 270)
			(unlocked yes)
			(layer "F.Fab")
			(hide yes)
			(effects
				(font
					(size 1.016 1.016)
					(thickness 0.1524)
				)
			)
		)
		(duplicate_pad_numbers_are_jumpers no)
		(fp_line
			(start -0.7493 1.651)
			(end -0.7493 1.1811)
			(stroke
				(width 0.3302)
				(type default)
			)
			(layer "F.SilkS")
		)
		(fp_line
			(start 0.7493 1.651)
			(end 0.7493 1.1811)
			(stroke
				(width 0.3302)
				(type default)
			)
			(layer "F.SilkS")
		)
		(fp_line
			(start -0.5969 1.5494)
			(end 0.5842 1.5494)
			(stroke
				(width 0.508)
				(type default)
			)
			(layer "F.SilkS")
		)
		(fp_line
			(start -0.6604 1.3716)
			(end -0.6604 -1.3716)
			(stroke
				(width 0.1524)
				(type default)
			)
			(layer "F.SilkS")
		)
		(fp_line
			(start 0.6604 1.3716)
			(end -0.6604 1.3716)
			(stroke
				(width 0.1524)
				(type default)
			)
			(layer "F.SilkS")
		)
		(fp_line
			(start -0.6604 -1.3716)
			(end 0.6604 -1.3716)
			(stroke
				(width 0.1524)
				(type default)
			)
			(layer "F.SilkS")
		)
		(fp_line
			(start 0.6604 -1.3716)
			(end 0.6604 1.3716)
			(stroke
				(width 0.1524)
				(type default)
			)
			(layer "F.SilkS")
		)
		(fp_rect
			(start -0.6223 1.3335)
			(end 0.6223 -1.3335)
			(stroke
				(width 0)
				(type default)
			)
			(fill no)
			(layer "F.CrtYd")
		)
		(fp_rect
			(start -0.6223 1.3335)
			(end 0.6223 -1.3335)
			(stroke
				(width 0)
				(type default)
			)
			(fill no)
			(layer "F.Fab")
		)
		(pad "A" smd custom
			(at 0 -0.762 270)
			(size 0.2159 0.2159)
			(layers "F.Cu" "F.Mask" "F.Paste")
			(net "LED_R_9")
			(options
				(clearance outline)
				(anchor circle)
			)
			(primitives
				(gr_poly
					(pts
						(arc
							(start -0.3302 -0.4318)
							(mid -0.402042 -0.402042)
							(end -0.4318 -0.3302)
						)
						(arc
							(start -0.4318 0.3302)
							(mid -0.402042 0.402042)
							(end -0.3302 0.4318)
						)
						(arc
							(start 0.3302 0.4318)
							(mid 0.402042 0.402042)
							(end 0.4318 0.3302)
						)
						(arc
							(start 0.4318 -0.3302)
							(mid 0.402042 -0.402042)
							(end 0.3302 -0.4318)
						)
					)
					(width 0)
					(fill yes)
				)
			)
		)
		(pad "K" smd custom
			(at 0 0.762 270)
			(size 0.2159 0.2159)
			(layers "F.Cu" "F.Mask" "F.Paste")
			(net "LED_Q_9")
			(options
				(clearance outline)
				(anchor circle)
			)
			(primitives
				(gr_poly
					(pts
						(arc
							(start -0.3302 -0.4318)
							(mid -0.402042 -0.402042)
							(end -0.4318 -0.3302)
						)
						(arc
							(start -0.4318 0.3302)
							(mid -0.402042 0.402042)
							(end -0.3302 0.4318)
						)
						(arc
							(start 0.3302 0.4318)
							(mid 0.402042 0.402042)
							(end 0.4318 0.3302)
						)
						(arc
							(start 0.4318 -0.3302)
							(mid 0.402042 -0.402042)
							(end 0.3302 -0.4318)
						)
					)
					(width 0)
					(fill yes)
				)
			)
		)
	)
	(footprint ""
		(layer "F.Cu")
		(at 62.0522 -58.928 180)
		(property "Reference" "C284"
			(at 0 0 180)
			(layer "F.SilkS")
			(hide yes)
			(effects
				(font
					(size 1.27 1.27)
				)
			)
		)
		(property "Value" "SCD01U16V2KX-3GP"
			(at 1.1811 -2.7051 180)
			(unlocked yes)
			(layer "F.Fab")
			(hide yes)
			(effects
				(font
					(size 1.016 1.016)
					(thickness 0.1524)
				)
			)
		)
		(property "Device Type" "C402H22"
			(at 1.1811 -4.2291 180)
			(unlocked yes)
			(layer "F.Fab")
			(hide yes)
			(effects
				(font
					(size 1.016 1.016)
					(thickness 0.1524)
				)
			)
		)
		(duplicate_pad_numbers_are_jumpers no)
		(fp_rect
			(start -0.4318 0.9525)
			(end 0.4318 -0.9525)
			(stroke
				(width 0)
				(type default)
			)
			(fill no)
			(layer "F.CrtYd")
		)
		(fp_rect
			(start -0.4318 0.9525)
			(end 0.4318 -0.9525)
			(stroke
				(width 0)
				(type default)
			)
			(fill no)
			(layer "F.Fab")
		)
		(pad "1" smd custom
			(at 0 -0.4445 180)
			(size 0.1524 0.1524)
			(layers "F.Cu" "F.Mask" "F.Paste")
			(net "P3V3_STBY")
			(options
				(clearance outline)
				(anchor circle)
			)
			(primitives
				(gr_poly
					(pts
						(arc
							(start 0.3048 -0.2032)
							(mid 0.275042 -0.275042)
							(end 0.2032 -0.3048)
						)
						(arc
							(start -0.2032 -0.3048)
							(mid -0.275042 -0.275042)
							(end -0.3048 -0.2032)
						)
						(arc
							(start -0.3048 0.2032)
							(mid -0.275042 0.275042)
							(end -0.2032 0.3048)
						)
						(arc
							(start 0.2032 0.3048)
							(mid 0.275042 0.275042)
							(end 0.3048 0.2032)
						)
					)
					(width 0)
					(fill yes)
				)
			)
		)
		(pad "2" smd custom
			(at 0 0.4445 180)
			(size 0.1524 0.1524)
			(layers "F.Cu" "F.Mask" "F.Paste")
			(net "GND")
			(options
				(clearance outline)
				(anchor circle)
			)
			(primitives
				(gr_poly
					(pts
						(arc
							(start 0.3048 -0.2032)
							(mid 0.275042 -0.275042)
							(end 0.2032 -0.3048)
						)
						(arc
							(start -0.2032 -0.3048)
							(mid -0.275042 -0.275042)
							(end -0.3048 -0.2032)
						)
						(arc
							(start -0.3048 0.2032)
							(mid -0.275042 0.275042)
							(end -0.2032 0.3048)
						)
						(arc
							(start 0.2032 0.3048)
							(mid 0.275042 0.275042)
							(end 0.3048 0.2032)
						)
					)
					(width 0)
					(fill yes)
				)
			)
		)
	)
	(footprint ""
		(layer "F.Cu")
		(at 152.527 -91.8464 90)
		(property "Reference" "X3"
			(at 0 0 90)
			(layer "F.SilkS")
			(hide yes)
			(effects
				(font
					(size 1.27 1.27)
				)
			)
		)
		(property "Value" "XTAL-25MHZ-266-GP"
			(at 0 -4.182618 90)
			(unlocked yes)
			(layer "F.Fab")
			(hide yes)
			(effects
				(font
					(size 1.016 1.016)
					(thickness 0.1524)
				)
			)
		)
		(property "Device Type" "OSC-3225-4P-4H32"
			(at 0 -5.706618 90)
			(unlocked yes)
			(layer "F.Fab")
			(hide yes)
			(effects
				(font
					(size 1.016 1.016)
					(thickness 0.1524)
				)
			)
		)
		(duplicate_pad_numbers_are_jumpers no)
		(fp_line
			(start 2.1209 -1.5494)
			(end -2.1209 -1.5494)
			(stroke
				(width 0.1524)
				(type default)
			)
			(layer "F.SilkS")
		)
		(fp_line
			(start -2.1209 -1.5494)
			(end -2.1209 1.5494)
			(stroke
				(width 0.1524)
				(type default)
			)
			(layer "F.SilkS")
		)
		(fp_line
			(start 2.1209 1.5494)
			(end 2.1209 -1.5494)
			(stroke
				(width 0.1524)
				(type default)
			)
			(layer "F.SilkS")
		)
		(fp_line
			(start -2.1209 1.5494)
			(end 2.1209 1.5494)
			(stroke
				(width 0.1524)
				(type default)
			)
			(layer "F.SilkS")
		)
		(fp_line
			(start -1.3208 1.651)
			(end -2.2098 1.651)
			(stroke
				(width 0.3302)
				(type default)
			)
			(layer "F.SilkS")
		)
		(fp_line
			(start -2.2098 1.651)
			(end -2.2098 0.6858)
			(stroke
				(width 0.3302)
				(type default)
			)
			(layer "F.SilkS")
		)
		(fp_poly
			(pts
				(xy -2.6289 1.1938) (xy -2.6289 0.3302) (xy -2.1971 0.762)
			)
			(stroke
				(width 0)
				(type default)
			)
			(fill yes)
			(layer "F.SilkS")
		)
		(fp_rect
			(start -1.6002 1.2446)
			(end 1.6002 -1.2446)
			(stroke
				(width 0)
				(type default)
			)
			(fill no)
			(layer "F.CrtYd")
		)
		(fp_poly
			(pts
				(xy -2.3749 1.8034) (xy -2.3749 -1.8034) (xy 2.3749 -1.8034) (xy 2.3749 1.8034) (xy 0.00254 1.8034)
				(xy 0.00254 1.2446) (xy 1.6002 1.2446) (xy 1.6002 -1.2446) (xy -1.6002 -1.2446) (xy -1.6002 1.2446)
				(xy -0.00254 1.2446) (xy -0.00254 1.8034)
			)
			(stroke
				(width 0)
				(type default)
			)
			(fill no)
			(layer "F.CrtYd")
		)
		(fp_rect
			(start -2.3749 1.8034)
			(end 2.3749 -1.8034)
			(stroke
				(width 0)
				(type default)
			)
			(fill no)
			(layer "F.Fab")
		)
		(pad "1" smd rect
			(at -1.171448 0.756412 90)
			(size 1.397 1.0668)
			(layers "F.Cu" "F.Mask" "F.Paste")
			(net "XTAL_X2")
		)
		(pad "2" smd rect
			(at 1.171448 0.756412 90)
			(size 1.397 1.0668)
			(layers "F.Cu" "F.Mask" "F.Paste")
			(net "GND")
		)
		(pad "3" smd rect
			(at 1.171448 -0.756412 90)
			(size 1.397 1.0668)
			(layers "F.Cu" "F.Mask" "F.Paste")
			(net "XTAL_X1")
		)
		(pad "4" smd rect
			(at -1.171448 -0.756412 90)
			(size 1.397 1.0668)
			(layers "F.Cu" "F.Mask" "F.Paste")
			(net "GND")
		)
		(zone
			(layer "F.Cu")
			(hatch none 0.5)
			(connect_pads
				(clearance 0)
			)
			(min_thickness 0.25)
			(keepout
				(tracks not_allowed)
				(vias allowed)
				(pads allowed)
				(copperpour not_allowed)
				(footprints allowed)
			)
			(placement
				(enabled no)
				(sheetname "")
			)
			(fill
				(thermal_gap 0.5)
				(thermal_bridge_width 0.5)
				(island_removal_mode 0)
			)
			(polygon
				(pts
					(xy 152.5778 -91.7956) (xy 152.5778 -91.8972) (xy 152.4762 -91.8972) (xy 152.4762 -91.7956)
				)
			)
		)
		(zone
			(layer "F.Cu")
			(hatch none 0.5)
			(connect_pads
				(clearance 0)
			)
			(min_thickness 0.25)
			(keepout
				(tracks allowed)
				(vias not_allowed)
				(pads allowed)
				(copperpour not_allowed)
				(footprints allowed)
			)
			(placement
				(enabled no)
				(sheetname "")
			)
			(fill
				(thermal_gap 0.5)
				(thermal_bridge_width 0.5)
				(island_removal_mode 0)
			)
			(polygon
				(pts
					(xy 151.237188 -91.373452) (xy 151.237188 -92.319348) (xy 152.303988 -92.319348) (xy 152.303988 -93.716348)
					(xy 152.750012 -93.716348) (xy 152.750012 -92.319348) (xy 153.816812 -92.319348) (xy 153.816812 -91.373452)
					(xy 152.750012 -91.373452) (xy 152.750012 -89.976452) (xy 152.303988 -89.976452) (xy 152.303988 -91.373452)
				)
			)
		)
	)
	(footprint ""
		(layer "F.Cu")
		(at 59.182 -47.244 90)
		(property "Reference" "PL2"
			(at 0 0 90)
			(layer "F.SilkS")
			(hide yes)
			(effects
				(font
					(size 1.27 1.27)
				)
			)
		)
		(property "Value" "BLM21PG220SN1DGP"
			(at 0.0254 -5.6896 90)
			(unlocked yes)
			(layer "F.Fab")
			(hide yes)
			(effects
				(font
					(size 1.016 1.016)
					(thickness 0.1524)
				)
			)
		)
		(property "Device Type" "L20125H42"
			(at 0.0254 -7.5946 90)
			(unlocked yes)
			(layer "F.Fab")
			(hide yes)
			(effects
				(font
					(size 1.016 1.016)
					(thickness 0.1524)
				)
			)
		)
		(duplicate_pad_numbers_are_jumpers no)
		(fp_line
			(start 0.9144 -1.7018)
			(end -0.9144 -1.7018)
			(stroke
				(width 0.1524)
				(type default)
			)
			(layer "F.SilkS")
		)
		(fp_line
			(start -0.9144 -1.7018)
			(end -0.9144 1.7018)
			(stroke
				(width 0.1524)
				(type default)
			)
			(layer "F.SilkS")
		)
		(fp_line
			(start 0.9144 1.7018)
			(end 0.9144 -1.7018)
			(stroke
				(width 0.1524)
				(type default)
			)
			(layer "F.SilkS")
		)
		(fp_line
			(start -0.9144 1.7018)
			(end 0.9144 1.7018)
			(stroke
				(width 0.1524)
				(type default)
			)
			(layer "F.SilkS")
		)
		(fp_rect
			(start -1.0033 1.778)
			(end 1.0033 -1.778)
			(stroke
				(width 0)
				(type default)
			)
			(fill no)
			(layer "F.CrtYd")
		)
		(fp_poly
			(pts
				(xy -1.0033 -1.778) (xy 1.0033 -1.778) (xy 1.0033 1.778) (xy -1.0033 1.778)
			)
			(stroke
				(width 0)
				(type default)
			)
			(fill no)
			(layer "F.Fab")
		)
		(pad "1" smd rect
			(at 0 -0.9652 90)
			(size 1.397 1.143)
			(layers "F.Cu" "F.Mask" "F.Paste")
			(net "P12V")
		)
		(pad "2" smd rect
			(at 0 0.9652 90)
			(size 1.397 1.143)
			(layers "F.Cu" "F.Mask" "F.Paste")
			(net "P3V3_STBY_VIN")
		)
	)
	(footprint ""
		(layer "F.Cu")
		(at 48.641 -152.4)
		(property "Reference" "R164"
			(at 0 0 0)
			(layer "F.SilkS")
			(hide yes)
			(effects
				(font
					(size 1.27 1.27)
				)
			)
		)
		(property "Value" "4K7R2F-GP"
			(at 0.064008 -3.993896 0)
			(unlocked yes)
			(layer "F.Fab")
			(hide yes)
			(effects
				(font
					(size 1.016 1.016)
					(thickness 0.1524)
				)
			)
		)
		(property "Device Type" "R402H16"
			(at 0.064008 -5.517896 0)
			(unlocked yes)
			(layer "F.Fab")
			(hide yes)
			(effects
				(font
					(size 1.016 1.016)
					(thickness 0.1524)
				)
			)
		)
		(duplicate_pad_numbers_are_jumpers no)
		(fp_line
			(start -0.508 -0.9398)
			(end -0.508 0.9398)
			(stroke
				(width 0.1524)
				(type default)
			)
			(layer "F.SilkS")
		)
		(fp_line
			(start 0.508 -0.9398)
			(end -0.508 -0.9398)
			(stroke
				(width 0.1524)
				(type default)
			)
			(layer "F.SilkS")
		)
		(fp_rect
			(start -0.508 0.9398)
			(end 0.508 -0.9398)
			(stroke
				(width 0)
				(type default)
			)
			(fill no)
			(layer "F.CrtYd")
		)
		(fp_rect
			(start -0.508 0.9398)
			(end 0.508 -0.9398)
			(stroke
				(width 0)
				(type default)
			)
			(fill no)
			(layer "F.Fab")
		)
		(pad "1" smd custom
			(at 0 -0.4445)
			(size 0.1397 0.1397)
			(layers "F.Cu" "F.Mask" "F.Paste")
			(net "P3V3_STBY")
			(options
				(clearance outline)
				(anchor circle)
			)
			(primitives
				(gr_poly
					(pts
						(arc
							(start -0.1778 -0.2794)
							(mid -0.249642 -0.249642)
							(end -0.2794 -0.1778)
						)
						(arc
							(start -0.2794 0.1778)
							(mid -0.249642 0.249642)
							(end -0.1778 0.2794)
						)
						(arc
							(start 0.1778 0.2794)
							(mid 0.249642 0.249642)
							(end 0.2794 0.1778)
						)
						(arc
							(start 0.2794 -0.1778)
							(mid 0.249642 -0.249642)
							(end 0.1778 -0.2794)
						)
					)
					(width 0)
					(fill yes)
				)
			)
		)
		(pad "2" smd custom
			(at 0 0.4445)
			(size 0.1397 0.1397)
			(layers "F.Cu" "F.Mask" "F.Paste")
			(net "TEMP_2_A2")
			(options
				(clearance outline)
				(anchor circle)
			)
			(primitives
				(gr_poly
					(pts
						(arc
							(start -0.1778 -0.2794)
							(mid -0.249642 -0.249642)
							(end -0.2794 -0.1778)
						)
						(arc
							(start -0.2794 0.1778)
							(mid -0.249642 0.249642)
							(end -0.1778 0.2794)
						)
						(arc
							(start 0.1778 0.2794)
							(mid 0.249642 0.249642)
							(end 0.2794 0.1778)
						)
						(arc
							(start 0.2794 -0.1778)
							(mid 0.249642 -0.249642)
							(end 0.1778 -0.2794)
						)
					)
					(width 0)
					(fill yes)
				)
			)
		)
	)
)
